(kicad_pcb
	(version 20260206)
	(generator "pcbnew")
	(generator_version "10.0")
	(general
		(thickness 1.6)
		(legacy_teardrops no)
	)
	(paper "A4")
	(title_block
		(title "04192023_DAF0TMB3IC0_F0TG_MB_C_brd_V02_OCP.brd")
		(comment 1 "Grand Teton / footprints 4241-4246 of 8354")
	)
	(layers
		(0 "F.Cu" signal "TOP")
		(4 "In1.Cu" signal "GND")
		(6 "In2.Cu" signal "IN1")
		(8 "In3.Cu" signal "GND1")
		(10 "In4.Cu" signal "IN2")
		(12 "In5.Cu" signal "GND2")
		(14 "In6.Cu" signal "IN3")
		(16 "In7.Cu" signal "GND3")
		(18 "In8.Cu" signal "VCC")
		(20 "In9.Cu" signal "VCC1")
		(22 "In10.Cu" signal "GND4")
		(24 "In11.Cu" signal "IN4")
		(26 "In12.Cu" signal "GND5")
		(28 "In13.Cu" signal "IN5")
		(30 "In14.Cu" signal "GND6")
		(32 "In15.Cu" signal "IN6")
		(34 "In16.Cu" signal "GND7")
		(2 "B.Cu" signal "BOTTOM")
		(9 "F.Adhes" user "F.Adhesive")
		(11 "B.Adhes" user "B.Adhesive")
		(13 "F.Paste" user "Package Geometry/Pastemask Top")
		(15 "B.Paste" user "Package Geometry/Pastemask Bottom")
		(5 "F.SilkS" user "Ref Des/Silkscreen Top")
		(7 "B.SilkS" user "Ref Des/Silkscreen Bottom")
		(1 "F.Mask" user "Board Geometry/Soldermask Top")
		(3 "B.Mask" user "Board Geometry/Soldermask Bottom")
		(17 "Dwgs.User" user "User.Drawings")
		(19 "Cmts.User" user "User.Comments")
		(21 "Eco1.User" user "User.Eco1")
		(23 "Eco2.User" user "User.Eco2")
		(25 "Edge.Cuts" user "Board Geometry/Outline")
		(27 "Margin" user)
		(31 "F.CrtYd" user "Package Geometry/Place Bound Top")
		(29 "B.CrtYd" user "Package Geometry/Place Bound Bottom")
		(35 "F.Fab" user "Ref Des/Assembly Top")
		(33 "B.Fab" user "Ref Des/Assembly Bottom")
	)
	(footprint ""
		(layer "F.Cu")
		(at 375.369074 -177.88636 -90)
		(property "Reference" "PC474_2"
			(at 0 0 270)
			(layer "F.SilkS")
			(hide yes)
			(effects
				(font
					(size 1.27 1.27)
				)
			)
		)
		(property "Value" ""
			(at 0 0 270)
			(layer "F.Fab")
			(effects
				(font
					(size 1.27 1.27)
				)
			)
		)
		(duplicate_pad_numbers_are_jumpers no)
		(fp_line
			(start -0.7874 0.4064)
			(end -0.7874 -0.4064)
			(stroke
				(width 0.1524)
				(type default)
			)
			(layer "F.SilkS")
		)
		(fp_line
			(start 0.7874 0.4064)
			(end -0.7874 0.4064)
			(stroke
				(width 0.1524)
				(type default)
			)
			(layer "F.SilkS")
		)
		(fp_line
			(start -0.7874 -0.4064)
			(end 0.7874 -0.4064)
			(stroke
				(width 0.1524)
				(type default)
			)
			(layer "F.SilkS")
		)
		(fp_line
			(start 0.7874 -0.4064)
			(end 0.7874 0.4064)
			(stroke
				(width 0.1524)
				(type default)
			)
			(layer "F.SilkS")
		)
		(fp_line
			(start -0.67945 0.3048)
			(end -0.67945 -0.305054)
			(stroke
				(width 0.1)
				(type default)
			)
			(layer "F.Fab")
		)
		(fp_line
			(start -0.12065 0.3048)
			(end -0.67945 0.3048)
			(stroke
				(width 0.1)
				(type default)
			)
			(layer "F.Fab")
		)
		(fp_line
			(start 0.120396 0.3048)
			(end 0.120396 0.2794)
			(stroke
				(width 0.1)
				(type default)
			)
			(layer "F.Fab")
		)
		(fp_line
			(start 0.67945 0.3048)
			(end 0.120396 0.3048)
			(stroke
				(width 0.1)
				(type default)
			)
			(layer "F.Fab")
		)
		(fp_line
			(start -0.12065 0.2794)
			(end -0.12065 0.3048)
			(stroke
				(width 0.1)
				(type default)
			)
			(layer "F.Fab")
		)
		(fp_line
			(start 0.120396 0.2794)
			(end -0.12065 0.2794)
			(stroke
				(width 0.1)
				(type default)
			)
			(layer "F.Fab")
		)
		(fp_line
			(start -0.12065 -0.2794)
			(end 0.12065 -0.2794)
			(stroke
				(width 0.1)
				(type default)
			)
			(layer "F.Fab")
		)
		(fp_line
			(start 0.12065 -0.2794)
			(end 0.12065 -0.3048)
			(stroke
				(width 0.1)
				(type default)
			)
			(layer "F.Fab")
		)
		(fp_line
			(start 0.12065 -0.3048)
			(end 0.67945 -0.3048)
			(stroke
				(width 0.1)
				(type default)
			)
			(layer "F.Fab")
		)
		(fp_line
			(start 0.67945 -0.3048)
			(end 0.67945 0.3048)
			(stroke
				(width 0.1)
				(type default)
			)
			(layer "F.Fab")
		)
		(fp_line
			(start -0.67945 -0.305054)
			(end -0.12065 -0.305054)
			(stroke
				(width 0.1)
				(type default)
			)
			(layer "F.Fab")
		)
		(fp_line
			(start -0.12065 -0.305054)
			(end -0.12065 -0.2794)
			(stroke
				(width 0.1)
				(type default)
			)
			(layer "F.Fab")
		)
		(pad "1" smd circle
			(at -0.40005 0 270)
			(size 0 0)
			(layers "F.Cu" "F.Mask" "F.Paste")
			(net "PVDDCR_CPU0_P0_VCCS")
		)
		(pad "2" smd circle
			(at 0.40005 0 270)
			(size 0 0)
			(layers "F.Cu" "F.Mask" "F.Paste")
			(net "GND")
		)
	)
	(footprint ""
		(layer "F.Cu")
		(at 336.195416 -24.617172 -90)
		(property "Reference" "Q30"
			(at -2.829052 -0.126492 0)
			(unlocked yes)
			(layer "F.SilkS")
			(effects
				(font
					(size 0.7874 0.5842)
					(thickness 0.1524)
				)
			)
		)
		(property "Value" ""
			(at 0 0 270)
			(layer "F.Fab")
			(effects
				(font
					(size 1.27 1.27)
				)
			)
		)
		(duplicate_pad_numbers_are_jumpers no)
		(fp_line
			(start -1.8796 1.651)
			(end -1.8796 -1.651)
			(stroke
				(width 0.1524)
				(type default)
			)
			(layer "F.SilkS")
		)
		(fp_line
			(start 1.8796 1.651)
			(end -1.8796 1.651)
			(stroke
				(width 0.1524)
				(type default)
			)
			(layer "F.SilkS")
		)
		(fp_line
			(start -1.8796 -1.651)
			(end 1.8796 -1.651)
			(stroke
				(width 0.1524)
				(type default)
			)
			(layer "F.SilkS")
		)
		(fp_line
			(start 1.8796 -1.651)
			(end 1.8796 1.651)
			(stroke
				(width 0.1524)
				(type default)
			)
			(layer "F.SilkS")
		)
		(fp_line
			(start -0.700024 1.500124)
			(end -0.700024 -1.500124)
			(stroke
				(width 0.1)
				(type default)
			)
			(layer "F.Fab")
		)
		(fp_line
			(start 0.700024 1.500124)
			(end -0.700024 1.500124)
			(stroke
				(width 0.1)
				(type default)
			)
			(layer "F.Fab")
		)
		(fp_line
			(start -0.700024 -1.500124)
			(end 0.700024 -1.500124)
			(stroke
				(width 0.1)
				(type default)
			)
			(layer "F.Fab")
		)
		(fp_line
			(start 0.700024 -1.500124)
			(end 0.700024 1.500124)
			(stroke
				(width 0.1)
				(type default)
			)
			(layer "F.Fab")
		)
		(pad "D" smd rect
			(at 1.119886 0 180)
			(size 1.016 1.2192)
			(layers "F.Cu" "F.Mask" "F.Paste")
			(net "LED_BIOS_DBG_MODE_N")
		)
		(pad "G" smd rect
			(at -1.119886 -0.999998 180)
			(size 1.016 1.2192)
			(layers "F.Cu" "F.Mask" "F.Paste")
			(net "BIOS_DEBUG_MODE")
		)
		(pad "S" smd rect
			(at -1.119886 0.999998 180)
			(size 1.016 1.2192)
			(layers "F.Cu" "F.Mask" "F.Paste")
			(net "GND")
		)
	)
	(footprint ""
		(layer "F.Cu")
		(at 109.575854 -256.012442 90)
		(property "Reference" "C2410"
			(at 0 0 90)
			(layer "F.SilkS")
			(hide yes)
			(effects
				(font
					(size 1.27 1.27)
				)
			)
		)
		(property "Value" ""
			(at 0 0 90)
			(layer "F.Fab")
			(effects
				(font
					(size 1.27 1.27)
				)
			)
		)
		(duplicate_pad_numbers_are_jumpers no)
		(fp_line
			(start 0.7874 -0.4064)
			(end 0.7874 0.4064)
			(stroke
				(width 0.1524)
				(type default)
			)
			(layer "F.SilkS")
		)
		(fp_line
			(start -0.7874 -0.4064)
			(end 0.7874 -0.4064)
			(stroke
				(width 0.1524)
				(type default)
			)
			(layer "F.SilkS")
		)
		(fp_line
			(start 0.7874 0.4064)
			(end -0.7874 0.4064)
			(stroke
				(width 0.1524)
				(type default)
			)
			(layer "F.SilkS")
		)
		(fp_line
			(start -0.7874 0.4064)
			(end -0.7874 -0.4064)
			(stroke
				(width 0.1524)
				(type default)
			)
			(layer "F.SilkS")
		)
		(fp_line
			(start -0.12065 -0.305054)
			(end -0.12065 -0.2794)
			(stroke
				(width 0.1)
				(type default)
			)
			(layer "F.Fab")
		)
		(fp_line
			(start -0.67945 -0.305054)
			(end -0.12065 -0.305054)
			(stroke
				(width 0.1)
				(type default)
			)
			(layer "F.Fab")
		)
		(fp_line
			(start 0.67945 -0.3048)
			(end 0.67945 0.3048)
			(stroke
				(width 0.1)
				(type default)
			)
			(layer "F.Fab")
		)
		(fp_line
			(start 0.12065 -0.3048)
			(end 0.67945 -0.3048)
			(stroke
				(width 0.1)
				(type default)
			)
			(layer "F.Fab")
		)
		(fp_line
			(start 0.12065 -0.2794)
			(end 0.12065 -0.3048)
			(stroke
				(width 0.1)
				(type default)
			)
			(layer "F.Fab")
		)
		(fp_line
			(start -0.12065 -0.2794)
			(end 0.12065 -0.2794)
			(stroke
				(width 0.1)
				(type default)
			)
			(layer "F.Fab")
		)
		(fp_line
			(start 0.120396 0.2794)
			(end -0.12065 0.2794)
			(stroke
				(width 0.1)
				(type default)
			)
			(layer "F.Fab")
		)
		(fp_line
			(start -0.12065 0.2794)
			(end -0.12065 0.3048)
			(stroke
				(width 0.1)
				(type default)
			)
			(layer "F.Fab")
		)
		(fp_line
			(start 0.67945 0.3048)
			(end 0.120396 0.3048)
			(stroke
				(width 0.1)
				(type default)
			)
			(layer "F.Fab")
		)
		(fp_line
			(start 0.120396 0.3048)
			(end 0.120396 0.2794)
			(stroke
				(width 0.1)
				(type default)
			)
			(layer "F.Fab")
		)
		(fp_line
			(start -0.12065 0.3048)
			(end -0.67945 0.3048)
			(stroke
				(width 0.1)
				(type default)
			)
			(layer "F.Fab")
		)
		(fp_line
			(start -0.67945 0.3048)
			(end -0.67945 -0.305054)
			(stroke
				(width 0.1)
				(type default)
			)
			(layer "F.Fab")
		)
		(pad "1" smd circle
			(at -0.40005 0 90)
			(size 0 0)
			(layers "F.Cu" "F.Mask" "F.Paste")
			(net "PVDDCR_SOC_P1")
		)
		(pad "2" smd circle
			(at 0.40005 0 90)
			(size 0 0)
			(layers "F.Cu" "F.Mask" "F.Paste")
			(net "GND")
		)
	)
	(footprint ""
		(layer "F.Cu")
		(at 434.678836 -169.224452)
		(property "Reference" "R5009"
			(at 0 0 0)
			(layer "F.SilkS")
			(hide yes)
			(effects
				(font
					(size 1.27 1.27)
				)
			)
		)
		(property "Value" ""
			(at 0 0 0)
			(layer "F.Fab")
			(effects
				(font
					(size 1.27 1.27)
				)
			)
		)
		(duplicate_pad_numbers_are_jumpers no)
		(fp_line
			(start -0.7874 -0.4064)
			(end 0.7874 -0.4064)
			(stroke
				(width 0.1524)
				(type default)
			)
			(layer "F.SilkS")
		)
		(fp_line
			(start -0.7874 0.4064)
			(end -0.7874 -0.4064)
			(stroke
				(width 0.1524)
				(type default)
			)
			(layer "F.SilkS")
		)
		(fp_line
			(start 0.7874 -0.4064)
			(end 0.7874 0.4064)
			(stroke
				(width 0.1524)
				(type default)
			)
			(layer "F.SilkS")
		)
		(fp_line
			(start 0.7874 0.4064)
			(end -0.7874 0.4064)
			(stroke
				(width 0.1524)
				(type default)
			)
			(layer "F.SilkS")
		)
		(fp_line
			(start -0.67945 -0.305054)
			(end -0.12065 -0.305054)
			(stroke
				(width 0.1)
				(type default)
			)
			(layer "F.Fab")
		)
		(fp_line
			(start -0.67945 0.3048)
			(end -0.67945 -0.305054)
			(stroke
				(width 0.1)
				(type default)
			)
			(layer "F.Fab")
		)
		(fp_line
			(start -0.12065 -0.305054)
			(end -0.12065 -0.2794)
			(stroke
				(width 0.1)
				(type default)
			)
			(layer "F.Fab")
		)
		(fp_line
			(start -0.12065 -0.2794)
			(end 0.12065 -0.2794)
			(stroke
				(width 0.1)
				(type default)
			)
			(layer "F.Fab")
		)
		(fp_line
			(start -0.12065 0.2794)
			(end -0.12065 0.3048)
			(stroke
				(width 0.1)
				(type default)
			)
			(layer "F.Fab")
		)
		(fp_line
			(start -0.12065 0.3048)
			(end -0.67945 0.3048)
			(stroke
				(width 0.1)
				(type default)
			)
			(layer "F.Fab")
		)
		(fp_line
			(start 0.120396 0.2794)
			(end -0.12065 0.2794)
			(stroke
				(width 0.1)
				(type default)
			)
			(layer "F.Fab")
		)
		(fp_line
			(start 0.120396 0.3048)
			(end 0.120396 0.2794)
			(stroke
				(width 0.1)
				(type default)
			)
			(layer "F.Fab")
		)
		(fp_line
			(start 0.12065 -0.3048)
			(end 0.67945 -0.3048)
			(stroke
				(width 0.1)
				(type default)
			)
			(layer "F.Fab")
		)
		(fp_line
			(start 0.12065 -0.2794)
			(end 0.12065 -0.3048)
			(stroke
				(width 0.1)
				(type default)
			)
			(layer "F.Fab")
		)
		(fp_line
			(start 0.67945 -0.3048)
			(end 0.67945 0.3048)
			(stroke
				(width 0.1)
				(type default)
			)
			(layer "F.Fab")
		)
		(fp_line
			(start 0.67945 0.3048)
			(end 0.120396 0.3048)
			(stroke
				(width 0.1)
				(type default)
			)
			(layer "F.Fab")
		)
		(pad "1" smd circle
			(at -0.40005 0)
			(size 0 0)
			(layers "F.Cu" "F.Mask" "F.Paste")
			(net "PVDD11_S3_P0")
		)
		(pad "2" smd circle
			(at 0.40005 0)
			(size 0 0)
			(layers "F.Cu" "F.Mask" "F.Paste")
			(net "I3C_SPD_DDRGL_CPU0_LVC1_SDA")
		)
	)
	(footprint ""
		(layer "F.Cu")
		(at 103.505 -417.957)
		(property "Reference" "R3496"
			(at 0 0 0)
			(layer "F.SilkS")
			(hide yes)
			(effects
				(font
					(size 1.27 1.27)
				)
			)
		)
		(property "Value" ""
			(at 0 0 0)
			(layer "F.Fab")
			(effects
				(font
					(size 1.27 1.27)
				)
			)
		)
		(duplicate_pad_numbers_are_jumpers no)
		(fp_line
			(start -0.7874 -0.4064)
			(end 0.7874 -0.4064)
			(stroke
				(width 0.1524)
				(type default)
			)
			(layer "F.SilkS")
		)
		(fp_line
			(start -0.7874 0.4064)
			(end -0.7874 -0.4064)
			(stroke
				(width 0.1524)
				(type default)
			)
			(layer "F.SilkS")
		)
		(fp_line
			(start 0.7874 -0.4064)
			(end 0.7874 0.4064)
			(stroke
				(width 0.1524)
				(type default)
			)
			(layer "F.SilkS")
		)
		(fp_line
			(start 0.7874 0.4064)
			(end -0.7874 0.4064)
			(stroke
				(width 0.1524)
				(type default)
			)
			(layer "F.SilkS")
		)
		(fp_line
			(start -0.67945 -0.305054)
			(end -0.12065 -0.305054)
			(stroke
				(width 0.1)
				(type default)
			)
			(layer "F.Fab")
		)
		(fp_line
			(start -0.67945 0.3048)
			(end -0.67945 -0.305054)
			(stroke
				(width 0.1)
				(type default)
			)
			(layer "F.Fab")
		)
		(fp_line
			(start -0.12065 -0.305054)
			(end -0.12065 -0.2794)
			(stroke
				(width 0.1)
				(type default)
			)
			(layer "F.Fab")
		)
		(fp_line
			(start -0.12065 -0.2794)
			(end 0.12065 -0.2794)
			(stroke
				(width 0.1)
				(type default)
			)
			(layer "F.Fab")
		)
		(fp_line
			(start -0.12065 0.2794)
			(end -0.12065 0.3048)
			(stroke
				(width 0.1)
				(type default)
			)
			(layer "F.Fab")
		)
		(fp_line
			(start -0.12065 0.3048)
			(end -0.67945 0.3048)
			(stroke
				(width 0.1)
				(type default)
			)
			(layer "F.Fab")
		)
		(fp_line
			(start 0.120396 0.2794)
			(end -0.12065 0.2794)
			(stroke
				(width 0.1)
				(type default)
			)
			(layer "F.Fab")
		)
		(fp_line
			(start 0.120396 0.3048)
			(end 0.120396 0.2794)
			(stroke
				(width 0.1)
				(type default)
			)
			(layer "F.Fab")
		)
		(fp_line
			(start 0.12065 -0.3048)
			(end 0.67945 -0.3048)
			(stroke
				(width 0.1)
				(type default)
			)
			(layer "F.Fab")
		)
		(fp_line
			(start 0.12065 -0.2794)
			(end 0.12065 -0.3048)
			(stroke
				(width 0.1)
				(type default)
			)
			(layer "F.Fab")
		)
		(fp_line
			(start 0.67945 -0.3048)
			(end 0.67945 0.3048)
			(stroke
				(width 0.1)
				(type default)
			)
			(layer "F.Fab")
		)
		(fp_line
			(start 0.67945 0.3048)
			(end 0.120396 0.3048)
			(stroke
				(width 0.1)
				(type default)
			)
			(layer "F.Fab")
		)
		(pad "1" smd circle
			(at -0.40005 0)
			(size 0 0)
			(layers "F.Cu" "F.Mask" "F.Paste")
			(net "GPU_FPGA_EROT_RST_BUF_R_N")
		)
		(pad "2" smd circle
			(at 0.40005 0)
			(size 0 0)
			(layers "F.Cu" "F.Mask" "F.Paste")
			(net "GPU_FPGA_EROT_RST_BUF_N")
		)
	)
	(footprint ""
		(layer "F.Cu")
		(at 175.883062 -23.283672 180)
		(property "Reference" "PR4006"
			(at 0 0 180)
			(layer "F.SilkS")
			(hide yes)
			(effects
				(font
					(size 1.27 1.27)
				)
			)
		)
		(property "Value" ""
			(at 0 0 180)
			(layer "F.Fab")
			(effects
				(font
					(size 1.27 1.27)
				)
			)
		)
		(duplicate_pad_numbers_are_jumpers no)
		(fp_line
			(start 0.7874 0.4064)
			(end -0.7874 0.4064)
			(stroke
				(width 0.1524)
				(type default)
			)
			(layer "F.SilkS")
		)
		(fp_line
			(start 0.7874 -0.4064)
			(end 0.7874 0.4064)
			(stroke
				(width 0.1524)
				(type default)
			)
			(layer "F.SilkS")
		)
		(fp_line
			(start -0.7874 0.4064)
			(end -0.7874 -0.4064)
			(stroke
				(width 0.1524)
				(type default)
			)
			(layer "F.SilkS")
		)
		(fp_line
			(start -0.7874 -0.4064)
			(end 0.7874 -0.4064)
			(stroke
				(width 0.1524)
				(type default)
			)
			(layer "F.SilkS")
		)
		(fp_line
			(start 0.67945 0.3048)
			(end 0.120396 0.3048)
			(stroke
				(width 0.1)
				(type default)
			)
			(layer "F.Fab")
		)
		(fp_line
			(start 0.67945 -0.3048)
			(end 0.67945 0.3048)
			(stroke
				(width 0.1)
				(type default)
			)
			(layer "F.Fab")
		)
		(fp_line
			(start 0.12065 -0.2794)
			(end 0.12065 -0.3048)
			(stroke
				(width 0.1)
				(type default)
			)
			(layer "F.Fab")
		)
		(fp_line
			(start 0.12065 -0.3048)
			(end 0.67945 -0.3048)
			(stroke
				(width 0.1)
				(type default)
			)
			(layer "F.Fab")
		)
		(fp_line
			(start 0.120396 0.3048)
			(end 0.120396 0.2794)
			(stroke
				(width 0.1)
				(type default)
			)
			(layer "F.Fab")
		)
		(fp_line
			(start 0.120396 0.2794)
			(end -0.12065 0.2794)
			(stroke
				(width 0.1)
				(type default)
			)
			(layer "F.Fab")
		)
		(fp_line
			(start -0.12065 0.3048)
			(end -0.67945 0.3048)
			(stroke
				(width 0.1)
				(type default)
			)
			(layer "F.Fab")
		)
		(fp_line
			(start -0.12065 0.2794)
			(end -0.12065 0.3048)
			(stroke
				(width 0.1)
				(type default)
			)
			(layer "F.Fab")
		)
		(fp_line
			(start -0.12065 -0.2794)
			(end 0.12065 -0.2794)
			(stroke
				(width 0.1)
				(type default)
			)
			(layer "F.Fab")
		)
		(fp_line
			(start -0.12065 -0.305054)
			(end -0.12065 -0.2794)
			(stroke
				(width 0.1)
				(type default)
			)
			(layer "F.Fab")
		)
		(fp_line
			(start -0.67945 0.3048)
			(end -0.67945 -0.305054)
			(stroke
				(width 0.1)
				(type default)
			)
			(layer "F.Fab")
		)
		(fp_line
			(start -0.67945 -0.305054)
			(end -0.12065 -0.305054)
			(stroke
				(width 0.1)
				(type default)
			)
			(layer "F.Fab")
		)
		(pad "1" smd circle
			(at -0.40005 0 180)
			(size 0 0)
			(layers "F.Cu" "F.Mask" "F.Paste")
			(net "P12V_SCM_R")
		)
		(pad "2" smd circle
			(at 0.40005 0 180)
			(size 0 0)
			(layers "F.Cu" "F.Mask" "F.Paste")
			(net "P12V_SCM_AVIN_PD")
		)
	)
)
